(kicad_pcb
	(version 20240108)
	(generator "pcbnew")
	(generator_version "8.0")
	(general
		(thickness 1.62)
		(legacy_teardrops no)
	)
	(paper "A4")
	(title_block
		(title "Jetson Orin Baseboard")
		(date "2025-03-12")
		(rev "1.3.4")
		(company "Antmicro Ltd")
		(comment 1 "www.antmicro.com")
		(comment 9 "footprints 565-569 of 677")
	)
	(layers
		(0 "F.Cu" signal)
		(1 "In1.Cu" signal)
		(2 "In2.Cu" signal)
		(3 "In3.Cu" signal)
		(4 "In4.Cu" jumper)
		(5 "In5.Cu" signal)
		(6 "In6.Cu" signal)
		(31 "B.Cu" signal)
		(32 "B.Adhes" user "B.Adhesive")
		(33 "F.Adhes" user "F.Adhesive")
		(34 "B.Paste" user)
		(35 "F.Paste" user)
		(36 "B.SilkS" user "B.Silkscreen")
		(37 "F.SilkS" user "F.Silkscreen")
		(38 "B.Mask" user)
		(39 "F.Mask" user)
		(40 "Dwgs.User" user "User.Drawings")
		(41 "Cmts.User" user "User.Comments")
		(42 "Eco1.User" user "User.Eco1")
		(43 "Eco2.User" user "User.Eco2")
		(44 "Edge.Cuts" user)
		(45 "Margin" user)
		(46 "B.CrtYd" user "B.Courtyard")
		(47 "F.CrtYd" user "F.Courtyard")
		(48 "B.Fab" user)
		(49 "F.Fab" user)
	)
	(footprint "antmicro-footprints:C_0402_1005Metric"
		(layer "B.Cu")
		(at 126.735 90.75)
		(descr "Capacitor SMD 0402")
		(tags "capacitor SMD 0402")
		(property "Reference" "C19"
			(at 2.965 0.45 180)
			(layer "B.SilkS")
			(effects
				(font
					(size 0.7 0.7)
					(thickness 0.15)
				)
				(justify left bottom mirror)
			)
		)
		(property "Value" "C_220n_0402"
			(at 0 -1.4 180)
			(layer "B.Fab")
			(effects
				(font
					(size 0.7 0.7)
					(thickness 0.15)
				)
				(justify left bottom mirror)
			)
		)
		(property "Footprint" "antmicro-footprints:C_0402_1005Metric"
			(at 0 0 0)
			(layer "F.Fab")
			(hide yes)
			(effects
				(font
					(size 1.27 1.27)
					(thickness 0.15)
				)
			)
		)
		(property "Datasheet" "https://www.yageo.com/en/Chart/Download/pdf/CC0402KRX5R6BB224"
			(at 0 0 0)
			(layer "F.Fab")
			(hide yes)
			(effects
				(font
					(size 1.27 1.27)
					(thickness 0.15)
				)
			)
		)
		(property "Author" "Antmicro"
			(at 0 0 0)
			(layer "B.Fab")
			(hide yes)
			(effects
				(font
					(size 1 1)
					(thickness 0.15)
				)
				(justify mirror)
			)
		)
		(property "Dielectric" ""
			(at 0 0 0)
			(layer "B.Fab")
			(hide yes)
			(effects
				(font
					(size 1 1)
					(thickness 0.15)
				)
				(justify mirror)
			)
		)
		(property "License" "Apache-2.0"
			(at 0 0 0)
			(layer "B.Fab")
			(hide yes)
			(effects
				(font
					(size 1 1)
					(thickness 0.15)
				)
				(justify mirror)
			)
		)
		(property "MPN" "CC0402KRX5R6BB224"
			(at 0 0 0)
			(layer "B.Fab")
			(hide yes)
			(effects
				(font
					(size 1 1)
					(thickness 0.15)
				)
				(justify mirror)
			)
		)
		(property "Manufacturer" "YAGEO"
			(at 0 0 0)
			(layer "B.Fab")
			(hide yes)
			(effects
				(font
					(size 1 1)
					(thickness 0.15)
				)
				(justify mirror)
			)
		)
		(property "Val" "220n"
			(at 0 0 0)
			(layer "B.Fab")
			(hide yes)
			(effects
				(font
					(size 1 1)
					(thickness 0.15)
				)
				(justify mirror)
			)
		)
		(property "Voltage" ""
			(at 0 0 0)
			(layer "B.Fab")
			(hide yes)
			(effects
				(font
					(size 1 1)
					(thickness 0.15)
				)
				(justify mirror)
			)
		)
		(sheetname "M.2")
		(sheetfile "m-2.kicad_sch")
		(attr smd)
		(fp_rect
			(start -0.925 0.47)
			(end 0.925 -0.47)
			(stroke
				(width 0.05)
				(type default)
			)
			(fill none)
			(layer "B.CrtYd")
		)
		(fp_line
			(start -0.494 -0.248)
			(end 0.504 -0.248)
			(stroke
				(width 0.15)
				(type solid)
			)
			(layer "B.Fab")
		)
		(fp_line
			(start -0.494 0.25)
			(end -0.494 -0.248)
			(stroke
				(width 0.15)
				(type solid)
			)
			(layer "B.Fab")
		)
		(fp_line
			(start 0.504 -0.248)
			(end 0.504 0.25)
			(stroke
				(width 0.15)
				(type solid)
			)
			(layer "B.Fab")
		)
		(fp_line
			(start 0.504 0.25)
			(end -0.494 0.25)
			(stroke
				(width 0.15)
				(type solid)
			)
			(layer "B.Fab")
		)
		(fp_text user "${REFERENCE}"
			(at -0.932 -3.168 180)
			(layer "B.Fab")
			(hide yes)
			(effects
				(font
					(size 0.7 0.7)
					(thickness 0.15)
				)
				(justify left bottom mirror)
			)
		)
		(fp_text user "Author: Antmicro"
			(at -0.932 -4.17 180)
			(layer "B.Fab")
			(hide yes)
			(effects
				(font
					(size 0.7 0.7)
					(thickness 0.15)
				)
				(justify left bottom mirror)
			)
		)
		(fp_text user "License: Apache-2.0"
			(at -0.932 -5.17 180)
			(layer "B.Fab")
			(hide yes)
			(effects
				(font
					(size 0.7 0.7)
					(thickness 0.15)
				)
				(justify left bottom mirror)
			)
		)
		(pad "1" smd roundrect
			(at -0.48 0)
			(size 0.59 0.64)
			(layers "B.Cu" "B.Paste" "B.Mask")
			(roundrect_rratio 0.25)
			(net 93 "/M.2/C_PCIE0_TX2_N")
			(pintype "passive")
		)
		(pad "2" smd roundrect
			(at 0.48 0)
			(size 0.59 0.64)
			(layers "B.Cu" "B.Paste" "B.Mask")
			(roundrect_rratio 0.25)
			(net 445 "PCIE0_TX2_N")
			(pintype "passive")
		)
	)
	(footprint "antmicro-footprints:C_0402_1005Metric"
		(layer "B.Cu")
		(at 71.7 103.35 -90)
		(descr "Capacitor SMD 0402")
		(tags "capacitor SMD 0402")
		(property "Reference" "C56"
			(at -1.1 0.53 90)
			(layer "B.SilkS")
			(effects
				(font
					(size 0.7 0.7)
					(thickness 0.15)
				)
				(justify left bottom mirror)
			)
		)
		(property "Value" "C_10u_0402"
			(at -1.022927 -2.155213 90)
			(layer "B.Fab")
			(effects
				(font
					(size 0.7 0.7)
					(thickness 0.15)
				)
				(justify left bottom mirror)
			)
		)
		(property "Footprint" "antmicro-footprints:C_0402_1005Metric"
			(at 0 0 -90)
			(layer "F.Fab")
			(hide yes)
			(effects
				(font
					(size 1.27 1.27)
					(thickness 0.15)
				)
			)
		)
		(property "Datasheet" "https://www.yageo.com/en/Chart/Download/pdf/CC0402MRX5R5BB106"
			(at 0 0 -90)
			(layer "F.Fab")
			(hide yes)
			(effects
				(font
					(size 1.27 1.27)
					(thickness 0.15)
				)
			)
		)
		(property "Author" "Antmicro"
			(at -31.65 175.05 0)
			(layer "B.Fab")
			(hide yes)
			(effects
				(font
					(size 1 1)
					(thickness 0.15)
				)
				(justify mirror)
			)
		)
		(property "Dielectric" ""
			(at -31.65 175.05 0)
			(layer "B.Fab")
			(hide yes)
			(effects
				(font
					(size 1 1)
					(thickness 0.15)
				)
				(justify mirror)
			)
		)
		(property "License" "Apache-2.0"
			(at -31.65 175.05 0)
			(layer "B.Fab")
			(hide yes)
			(effects
				(font
					(size 1 1)
					(thickness 0.15)
				)
				(justify mirror)
			)
		)
		(property "MPN" "CC0402MRX5R5BB106"
			(at -31.65 175.05 0)
			(layer "B.Fab")
			(hide yes)
			(effects
				(font
					(size 1 1)
					(thickness 0.15)
				)
				(justify mirror)
			)
		)
		(property "Manufacturer" "YAGEO"
			(at -31.65 175.05 0)
			(layer "B.Fab")
			(hide yes)
			(effects
				(font
					(size 1 1)
					(thickness 0.15)
				)
				(justify mirror)
			)
		)
		(property "Val" "10u"
			(at -31.65 175.05 0)
			(layer "B.Fab")
			(hide yes)
			(effects
				(font
					(size 1 1)
					(thickness 0.15)
				)
				(justify mirror)
			)
		)
		(property "Voltage" ""
			(at -31.65 175.05 0)
			(layer "B.Fab")
			(hide yes)
			(effects
				(font
					(size 1 1)
					(thickness 0.15)
				)
				(justify mirror)
			)
		)
		(sheetname "USB Debug, DP")
		(sheetfile "usb.kicad_sch")
		(attr smd)
		(fp_rect
			(start -0.925 0.47)
			(end 0.925 -0.47)
			(stroke
				(width 0.05)
				(type default)
			)
			(fill none)
			(layer "B.CrtYd")
		)
		(fp_line
			(start -0.494 0.25)
			(end -0.494 -0.248)
			(stroke
				(width 0.15)
				(type solid)
			)
			(layer "B.Fab")
		)
		(fp_line
			(start 0.504 0.25)
			(end -0.494 0.25)
			(stroke
				(width 0.15)
				(type solid)
			)
			(layer "B.Fab")
		)
		(fp_line
			(start -0.494 -0.248)
			(end 0.504 -0.248)
			(stroke
				(width 0.15)
				(type solid)
			)
			(layer "B.Fab")
		)
		(fp_line
			(start 0.504 -0.248)
			(end 0.504 0.25)
			(stroke
				(width 0.15)
				(type solid)
			)
			(layer "B.Fab")
		)
		(fp_text user "${REFERENCE}"
			(at -0.939 -4.599 90)
			(layer "B.Fab")
			(hide yes)
			(effects
				(font
					(size 0.7 0.7)
					(thickness 0.15)
				)
				(justify left bottom mirror)
			)
		)
		(fp_text user "Author: Antmicro"
			(at -0.939 -3.399 90)
			(layer "B.Fab")
			(hide yes)
			(effects
				(font
					(size 0.7 0.7)
					(thickness 0.15)
				)
				(justify left bottom mirror)
			)
		)
		(fp_text user "License: Apache-2.0"
			(at -0.939 -5.799 90)
			(layer "B.Fab")
			(hide yes)
			(effects
				(font
					(size 0.7 0.7)
					(thickness 0.15)
				)
				(justify left bottom mirror)
			)
		)
		(pad "1" smd roundrect
			(at -0.48 0 270)
			(size 0.59 0.64)
			(layers "B.Cu" "B.Paste" "B.Mask")
			(roundrect_rratio 0.25)
			(net 1 "GND")
			(pintype "passive")
		)
		(pad "2" smd roundrect
			(at 0.48 0 270)
			(size 0.59 0.64)
			(layers "B.Cu" "B.Paste" "B.Mask")
			(roundrect_rratio 0.25)
			(net 87 "+3V3")
			(pintype "passive")
		)
	)
	(footprint "antmicro-footprints:C_0402_1005Metric"
		(layer "B.Cu")
		(at 47.3 80.1 90)
		(descr "Capacitor SMD 0402")
		(tags "capacitor SMD 0402")
		(property "Reference" "C150"
			(at 3.525 -0.5 90)
			(layer "B.SilkS")
			(effects
				(font
					(size 0.7 0.7)
					(thickness 0.15)
				)
				(justify left bottom mirror)
			)
		)
		(property "Value" "C_1u_25V_0402"
			(at 0 -1.4 -90)
			(layer "B.Fab")
			(effects
				(font
					(size 0.7 0.7)
					(thickness 0.15)
				)
				(justify left bottom mirror)
			)
		)
		(property "Footprint" "antmicro-footprints:C_0402_1005Metric"
			(at 0 0 90)
			(layer "F.Fab")
			(hide yes)
			(effects
				(font
					(size 1.27 1.27)
					(thickness 0.15)
				)
			)
		)
		(property "Datasheet" "https://www.murata.com/products/productdetail?partno=GRM155R61E105KE11%23"
			(at 0 0 90)
			(layer "F.Fab")
			(hide yes)
			(effects
				(font
					(size 1.27 1.27)
					(thickness 0.15)
				)
			)
		)
		(property "Author" "Antmicro"
			(at 128.55 31.65 0)
			(layer "B.Fab")
			(hide yes)
			(effects
				(font
					(size 1 1)
					(thickness 0.15)
				)
				(justify mirror)
			)
		)
		(property "Dielectric" "X5R"
			(at 128.55 31.65 0)
			(layer "B.Fab")
			(hide yes)
			(effects
				(font
					(size 1 1)
					(thickness 0.15)
				)
				(justify mirror)
			)
		)
		(property "License" "Apache-2.0"
			(at 128.55 31.65 0)
			(layer "B.Fab")
			(hide yes)
			(effects
				(font
					(size 1 1)
					(thickness 0.15)
				)
				(justify mirror)
			)
		)
		(property "MPN" "GRM155R61E105KE11J"
			(at 128.55 31.65 0)
			(layer "B.Fab")
			(hide yes)
			(effects
				(font
					(size 1 1)
					(thickness 0.15)
				)
				(justify mirror)
			)
		)
		(property "Manufacturer" "Murata"
			(at 128.55 31.65 0)
			(layer "B.Fab")
			(hide yes)
			(effects
				(font
					(size 1 1)
					(thickness 0.15)
				)
				(justify mirror)
			)
		)
		(property "Val" "1u"
			(at 128.55 31.65 0)
			(layer "B.Fab")
			(hide yes)
			(effects
				(font
					(size 1 1)
					(thickness 0.15)
				)
				(justify mirror)
			)
		)
		(property "Voltage" "25V"
			(at 128.55 31.65 0)
			(layer "B.Fab")
			(hide yes)
			(effects
				(font
					(size 1 1)
					(thickness 0.15)
				)
				(justify mirror)
			)
		)
		(sheetname "Supply")
		(sheetfile "supply.kicad_sch")
		(attr smd)
		(fp_rect
			(start -0.925 0.47)
			(end 0.925 -0.47)
			(stroke
				(width 0.05)
				(type default)
			)
			(fill none)
			(layer "B.CrtYd")
		)
		(fp_line
			(start 0.504 -0.248)
			(end 0.504 0.25)
			(stroke
				(width 0.15)
				(type solid)
			)
			(layer "B.Fab")
		)
		(fp_line
			(start -0.494 -0.248)
			(end 0.504 -0.248)
			(stroke
				(width 0.15)
				(type solid)
			)
			(layer "B.Fab")
		)
		(fp_line
			(start 0.504 0.25)
			(end -0.494 0.25)
			(stroke
				(width 0.15)
				(type solid)
			)
			(layer "B.Fab")
		)
		(fp_line
			(start -0.494 0.25)
			(end -0.494 -0.248)
			(stroke
				(width 0.15)
				(type solid)
			)
			(layer "B.Fab")
		)
		(fp_text user "${REFERENCE}"
			(at -0.932 -3.168 -90)
			(layer "B.Fab")
			(hide yes)
			(effects
				(font
					(size 0.7 0.7)
					(thickness 0.15)
				)
				(justify left bottom mirror)
			)
		)
		(fp_text user "License: Apache-2.0"
			(at -0.932 -5.17 -90)
			(layer "B.Fab")
			(hide yes)
			(effects
				(font
					(size 0.7 0.7)
					(thickness 0.15)
				)
				(justify left bottom mirror)
			)
		)
		(fp_text user "Author: Antmicro"
			(at -0.932 -4.17 -90)
			(layer "B.Fab")
			(hide yes)
			(effects
				(font
					(size 0.7 0.7)
					(thickness 0.15)
				)
				(justify left bottom mirror)
			)
		)
		(pad "1" smd roundrect
			(at -0.48 0 90)
			(size 0.59 0.64)
			(layers "B.Cu" "B.Paste" "B.Mask")
			(roundrect_rratio 0.25)
			(net 135 "Net-(Q18-G)")
			(pintype "passive")
		)
		(pad "2" smd roundrect
			(at 0.48 0 90)
			(size 0.59 0.64)
			(layers "B.Cu" "B.Paste" "B.Mask")
			(roundrect_rratio 0.25)
			(net 328 "/Supply/VCC_IN")
			(pintype "passive")
		)
	)
	(footprint "antmicro-footprints:R_0402_1005Metric"
		(layer "B.Cu")
		(at 46.9 88.6375)
		(descr "Resistor SMD 0402")
		(tags "resistor SMD 0402")
		(property "Reference" "R142"
			(at 0.335 -3.4775 180)
			(layer "B.SilkS")
			(effects
				(font
					(size 0.7 0.7)
					(thickness 0.15)
				)
				(justify left bottom mirror)
			)
		)
		(property "Value" "R_49k9_0402"
			(at 0 -1.4 180)
			(layer "B.Fab")
			(effects
				(font
					(size 0.7 0.7)
					(thickness 0.15)
				)
				(justify left bottom mirror)
			)
		)
		(property "Footprint" "antmicro-footprints:R_0402_1005Metric"
			(at 0 0 0)
			(layer "F.Fab")
			(hide yes)
			(effects
				(font
					(size 1.27 1.27)
					(thickness 0.15)
				)
			)
		)
		(property "Datasheet" "https://www.bourns.com/docs/product-datasheets/cr.pdf"
			(at 0 0 0)
			(layer "F.Fab")
			(hide yes)
			(effects
				(font
					(size 1.27 1.27)
					(thickness 0.15)
				)
			)
		)
		(property "Author" "Antmicro"
			(at 0 0 0)
			(layer "B.Fab")
			(hide yes)
			(effects
				(font
					(size 1 1)
					(thickness 0.15)
				)
				(justify mirror)
			)
		)
		(property "License" "Apache-2.0"
			(at 0 0 0)
			(layer "B.Fab")
			(hide yes)
			(effects
				(font
					(size 1 1)
					(thickness 0.15)
				)
				(justify mirror)
			)
		)
		(property "MPN" "CR0402-FX-4992GLF"
			(at 0 0 0)
			(layer "B.Fab")
			(hide yes)
			(effects
				(font
					(size 1 1)
					(thickness 0.15)
				)
				(justify mirror)
			)
		)
		(property "Manufacturer" "Bourns"
			(at 0 0 0)
			(layer "B.Fab")
			(hide yes)
			(effects
				(font
					(size 1 1)
					(thickness 0.15)
				)
				(justify mirror)
			)
		)
		(property "Tolerance" "1%"
			(at 0 0 0)
			(layer "B.Fab")
			(hide yes)
			(effects
				(font
					(size 1 1)
					(thickness 0.15)
				)
				(justify mirror)
			)
		)
		(property "Val" "49k9"
			(at 0 0 0)
			(layer "B.Fab")
			(hide yes)
			(effects
				(font
					(size 1 1)
					(thickness 0.15)
				)
				(justify mirror)
			)
		)
		(sheetname "Ethernet")
		(sheetfile "ethernet.kicad_sch")
		(attr smd)
		(fp_rect
			(start -0.925 0.47)
			(end 0.925 -0.47)
			(stroke
				(width 0.05)
				(type default)
			)
			(fill none)
			(layer "B.CrtYd")
		)
		(fp_rect
			(start -0.5 0.25)
			(end 0.5 -0.25)
			(stroke
				(width 0.15)
				(type solid)
			)
			(fill none)
			(layer "B.Fab")
		)
		(fp_text user "Author: Antmicro"
			(at -0.95 -4.169 180)
			(layer "B.Fab")
			(hide yes)
			(effects
				(font
					(size 0.7 0.7)
					(thickness 0.15)
				)
				(justify left bottom mirror)
			)
		)
		(fp_text user "${REFERENCE}"
			(at -0.95 -3.168 180)
			(layer "B.Fab")
			(hide yes)
			(effects
				(font
					(size 0.7 0.7)
					(thickness 0.15)
				)
				(justify left bottom mirror)
			)
		)
		(fp_text user "License: Apache-2.0"
			(at -0.95 -5.169 180)
			(layer "B.Fab")
			(hide yes)
			(effects
				(font
					(size 0.7 0.7)
					(thickness 0.15)
				)
				(justify left bottom mirror)
			)
		)
		(pad "1" smd roundrect
			(at -0.48 0)
			(size 0.59 0.64)
			(layers "B.Cu" "B.Paste" "B.Mask")
			(roundrect_rratio 0.25)
			(net 499 "/Ethernet/VSS")
			(pintype "passive")
		)
		(pad "2" smd roundrect
			(at 0.48 0)
			(size 0.59 0.64)
			(layers "B.Cu" "B.Paste" "B.Mask")
			(roundrect_rratio 0.25)
			(net 566 "/Ethernet/REF")
			(pintype "passive")
		)
	)
	(footprint "antmicro-footprints:R_0402_1005Metric"
		(layer "B.Cu")
		(at 53.9 116.8 -90)
		(descr "Resistor SMD 0402")
		(tags "resistor SMD 0402")
		(property "Reference" "R127"
			(at -1.35 -2.7 90)
			(layer "B.SilkS")
			(effects
				(font
					(size 0.7 0.7)
					(thickness 0.15)
				)
				(justify left bottom mirror)
			)
		)
		(property "Value" "R_27R_0402"
			(at 0 -1.4 90)
			(layer "B.Fab")
			(effects
				(font
					(size 0.7 0.7)
					(thickness 0.15)
				)
				(justify left bottom mirror)
			)
		)
		(property "Footprint" "antmicro-footprints:R_0402_1005Metric"
			(at 0 0 -90)
			(layer "F.Fab")
			(hide yes)
			(effects
				(font
					(size 1.27 1.27)
					(thickness 0.15)
				)
			)
		)
		(property "Datasheet" "https://www.bourns.com/docs/product-datasheets/cr.pdf"
			(at 0 0 -90)
			(layer "F.Fab")
			(hide yes)
			(effects
				(font
					(size 1.27 1.27)
					(thickness 0.15)
				)
			)
		)
		(property "Author" "Antmicro"
			(at -62.9 170.7 0)
			(layer "B.Fab")
			(hide yes)
			(effects
				(font
					(size 1 1)
					(thickness 0.15)
				)
				(justify mirror)
			)
		)
		(property "License" "Apache-2.0"
			(at -62.9 170.7 0)
			(layer "B.Fab")
			(hide yes)
			(effects
				(font
					(size 1 1)
					(thickness 0.15)
				)
				(justify mirror)
			)
		)
		(property "MPN" "CR0402-FX-27R0GLF"
			(at -62.9 170.7 0)
			(layer "B.Fab")
			(hide yes)
			(effects
				(font
					(size 1 1)
					(thickness 0.15)
				)
				(justify mirror)
			)
		)
		(property "Manufacturer" "Bourns"
			(at -62.9 170.7 0)
			(layer "B.Fab")
			(hide yes)
			(effects
				(font
					(size 1 1)
					(thickness 0.15)
				)
				(justify mirror)
			)
		)
		(property "Tolerance" "1%"
			(at -62.9 170.7 0)
			(layer "B.Fab")
			(hide yes)
			(effects
				(font
					(size 1 1)
					(thickness 0.15)
				)
				(justify mirror)
			)
		)
		(property "Val" "27R"
			(at -62.9 170.7 0)
			(layer "B.Fab")
			(hide yes)
			(effects
				(font
					(size 1 1)
					(thickness 0.15)
				)
				(justify mirror)
			)
		)
		(sheetname "USB Debug, DP")
		(sheetfile "usb.kicad_sch")
		(attr smd)
		(fp_rect
			(start -0.925 0.47)
			(end 0.925 -0.47)
			(stroke
				(width 0.05)
				(type default)
			)
			(fill none)
			(layer "B.CrtYd")
		)
		(fp_rect
			(start -0.5 0.25)
			(end 0.5 -0.25)
			(stroke
				(width 0.15)
				(type solid)
			)
			(fill none)
			(layer "B.Fab")
		)
		(fp_text user "Author: Antmicro"
			(at -0.95 -4.169 90)
			(layer "B.Fab")
			(hide yes)
			(effects
				(font
					(size 0.7 0.7)
					(thickness 0.15)
				)
				(justify left bottom mirror)
			)
		)
		(fp_text user "${REFERENCE}"
			(at -0.95 -3.168 90)
			(layer "B.Fab")
			(hide yes)
			(effects
				(font
					(size 0.7 0.7)
					(thickness 0.15)
				)
				(justify left bottom mirror)
			)
		)
		(fp_text user "License: Apache-2.0"
			(at -0.95 -5.169 90)
			(layer "B.Fab")
			(hide yes)
			(effects
				(font
					(size 0.7 0.7)
					(thickness 0.15)
				)
				(justify left bottom mirror)
			)
		)
		(pad "1" smd roundrect
			(at -0.48 0 270)
			(size 0.59 0.64)
			(layers "B.Cu" "B.Paste" "B.Mask")
			(roundrect_rratio 0.25)
			(net 313 "/USB Debug, DP/USB_FTDI_P")
			(pintype "passive")
		)
		(pad "2" smd roundrect
			(at 0.48 0 270)
			(size 0.59 0.64)
			(layers "B.Cu" "B.Paste" "B.Mask")
			(roundrect_rratio 0.25)
			(net 613 "/USB Debug, DP/USBC3_D_P")
			(pintype "passive")
		)
	)
)
